FILE_TYPE = MACRO_DRAWING;
SET COLOR_WIRE YELLOW;
SET COLOR_PROP ORANGE;
SET COLOR_DOT WHITE;
SET COLOR_ARC YELLOW;
SET COLOR_BODY GREEN;
SET COLOR_NOTE PURPLE;
SET PROP_DISPLAY VALUE;
SET PAGE_NUMBER P421;
FORCEADD OFFPAGE..1
(-7425 5625);
FORCEPROP 2 LAST $XR1 186 
J 0
(-7797 5625);
DISPLAY 0.638298 (-7797 5625);
PAINT MONO (-7797 5625);
FORCEPROP 2 LAST $XR0 185 
J 0
(-7677 5625);
DISPLAY 0.638298 (-7677 5625);
PAINT MONO (-7677 5625);
FORCEPROP 2 LAST CDS_LIB standard
J 0
(-7425 5625);
DISPLAY INVISIBLE (-7425 5625);
FORCEPROP 1 LAST OFFPAGE TRUE
J 0
(-7100 5500);
DISPLAY 0.872340 (-7100 5500);
DISPLAY INVISIBLE (-7100 5500);
FORCEPROP 1 LAST COMMENT_BODY TRUE
J 0
(-7300 5525);
DISPLAY 0.872340 (-7300 5525);
PAINT GREEN (-7300 5525);
DISPLAY INVISIBLE (-7300 5525);
FORCEPROP 2 LAST PATH I1
J 0
(-7375 5700);
DISPLAY 0.680851 (-7375 5700);
DISPLAY INVISIBLE (-7375 5700);
FORCEADD Q_RES..2
(-4100 5450);
FORCEPROP 1 LAST LOCATION R1085
J 0
(-4055 5575);
DISPLAY 0.978723 (-4055 5575);
FORCEPROP 0 LAST $SEC 1
J 0
(-4050 5625);
DISPLAY 0.680851 (-4050 5625);
PAINT MONO (-4050 5625);
DISPLAY INVISIBLE (-4050 5625);
FORCEPROP 0 LAST CDS_SEC 1
J 0
(-4050 5625);
DISPLAY 0.680851 (-4050 5625);
DISPLAY INVISIBLE (-4050 5625);
FORCEPROP 1 LASTPIN (-4100 5550) $PN 1
J 0
(-4095 5512);
DISPLAY 0.787234 (-4095 5512);
PAINT MONO (-4095 5512);
FORCEPROP 1 LASTPIN (-4100 5350) $PN 2
J 0
(-4095 5360);
DISPLAY 0.787234 (-4095 5360);
PAINT MONO (-4095 5360);
FORCEPROP 1 LAST VALUE 1K
J 0
(-4055 5525);
DISPLAY 0.978723 (-4055 5525);
FORCEPROP 1 LAST TOLERANCE 1%
J 0
(-4055 5475);
DISPLAY 0.978723 (-4055 5475);
FORCEPROP 1 LAST WATTAGE 1/20W
J 0
(-4060 5425);
DISPLAY 0.978723 (-4060 5425);
FORCEPROP 1 LAST MATERIAL CHIP
J 0
(-4060 5375);
DISPLAY 0.978723 (-4060 5375);
FORCEPROP 1 LAST PACK_TYPE 0201LF
J 0
(-4060 5275);
DISPLAY 0.978723 (-4060 5275);
FORCEPROP 2 LAST CDS_LIB pure_quanta
J 0
(-4100 5450);
DISPLAY INVISIBLE (-4100 5450);
FORCEPROP 1 LAST PATH I18
J 0
(-4050 5625);
DISPLAY 0.978723 (-4050 5625);
PAINT WHITE (-4050 5625);
DISPLAY INVISIBLE (-4050 5625);
FORCEPROP 1 LAST PART_NUMBER CS21001FE07
J 0
(-4060 5325);
DISPLAY 0.978723 (-4060 5325);
DISPLAY INVISIBLE (-4060 5325);
FORCEADD UNIVERSAL_GND..1
(-4100 5025);
FORCEPROP 3 LASTPIN (-4100 5075) SIG_NAME GND\g
J 0
(-4090 5085);
DISPLAY 0.659574 (-4090 5085);
PAINT MONO (-4090 5085);
DISPLAY INVISIBLE (-4090 5085);
FORCEPROP 2 LAST CDS_LIB pure_quanta_power
J 0
(-4100 5025);
DISPLAY INVISIBLE (-4100 5025);
FORCEPROP 1 LAST HDL_POWER GND
J 1
(-4075 4950);
DISPLAY 0.872340 (-4075 4950);
PAINT GREEN (-4075 4950);
DISPLAY INVISIBLE (-4075 4950);
FORCEPROP 1 LAST PATH I19
J 0
(-4025 5025);
DISPLAY 0.872340 (-4025 5025);
PAINT AQUA (-4025 5025);
DISPLAY INVISIBLE (-4025 5025);
FORCEADD OFFPAGE..3
R 2
(-7400 5575);
FORCEPROP 2 LAST $XR1 186 
J 0
(-7800 5575);
DISPLAY 0.638298 (-7800 5575);
PAINT MONO (-7800 5575);
FORCEPROP 2 LAST $XR0 185 
J 0
(-7680 5575);
DISPLAY 0.638298 (-7680 5575);
PAINT MONO (-7680 5575);
FORCEPROP 2 LAST CDS_LIB standard
J 0
(-7400 5575);
DISPLAY INVISIBLE (-7400 5575);
FORCEPROP 1 LAST OFFPAGE TRUE
J 2
(-7725 5450);
DISPLAY 0.872340 (-7725 5450);
PAINT GREEN (-7725 5450);
DISPLAY INVISIBLE (-7725 5450);
FORCEPROP 1 LAST COMMENT_BODY TRUE
J 2
(-7350 5475);
DISPLAY 0.872340 (-7350 5475);
PAINT GREEN (-7350 5475);
DISPLAY INVISIBLE (-7350 5475);
FORCEPROP 2 LAST PATH I2
J 0
(-7350 5650);
DISPLAY 0.680851 (-7350 5650);
DISPLAY INVISIBLE (-7350 5650);
FORCEADD UNIVERSAL_GND..1
(-4250 5375);
FORCEPROP 3 LASTPIN (-4250 5425) SIG_NAME GND\g
J 0
(-4240 5435);
DISPLAY 0.659574 (-4240 5435);
PAINT MONO (-4240 5435);
DISPLAY INVISIBLE (-4240 5435);
FORCEPROP 2 LAST CDS_LIB pure_quanta_power
J 0
(-4250 5375);
DISPLAY INVISIBLE (-4250 5375);
FORCEPROP 1 LAST HDL_POWER GND
J 1
(-4225 5300);
DISPLAY 0.872340 (-4225 5300);
PAINT GREEN (-4225 5300);
DISPLAY INVISIBLE (-4225 5300);
FORCEPROP 1 LAST PATH I20
J 0
(-4175 5375);
DISPLAY 0.872340 (-4175 5375);
PAINT AQUA (-4175 5375);
DISPLAY INVISIBLE (-4175 5375);
FORCEADD UNIVERSAL_GND..1
R 7
(-5250 5675);
FORCEPROP 3 LASTPIN (-5200 5675) SIG_NAME GND\g
J 0
(-5190 5685);
DISPLAY 0.659574 (-5190 5685);
PAINT MONO (-5190 5685);
DISPLAY INVISIBLE (-5190 5685);
FORCEPROP 2 LAST CDS_LIB pure_quanta_power
J 0
(-5250 5675);
DISPLAY INVISIBLE (-5250 5675);
FORCEPROP 1 LAST HDL_POWER GND
R 1
J 1
(-5325 5700);
DISPLAY 0.872340 (-5325 5700);
PAINT GREEN (-5325 5700);
DISPLAY INVISIBLE (-5325 5700);
FORCEPROP 1 LAST PATH I21
R 1
J 0
(-5250 5750);
DISPLAY 0.872340 (-5250 5750);
PAINT AQUA (-5250 5750);
DISPLAY INVISIBLE (-5250 5750);
FORCEADD P1V0..1
(-5250 6500);
FORCEPROP 3 LASTPIN (-5250 6450) SIG_NAME P1V8_CPU0_RT_1D\g
J 0
(-5240 6460);
DISPLAY 0.659574 (-5240 6460);
PAINT MONO (-5240 6460);
DISPLAY INVISIBLE (-5240 6460);
FORCEPROP 1 LAST HDL_POWER P1V8_CPU0_RT_1D
J 1
(-5250 6550);
DISPLAY 0.489362 (-5250 6550);
PAINT SKYBLUE (-5250 6550);
FORCEPROP 2 LAST CDS_LIB pure_quanta_power
J 0
(-5250 6500);
DISPLAY INVISIBLE (-5250 6500);
FORCEPROP 1 LAST PATH I22
J 0
(-5200 6525);
DISPLAY 0.872340 (-5200 6525);
PAINT AQUA (-5200 6525);
DISPLAY INVISIBLE (-5200 6525);
FORCEADD Q_CAP..1
(-5550 6150);
FORCEPROP 1 LAST LOCATION C989
J 0
(-5500 6250);
DISPLAY 0.787234 (-5500 6250);
PAINT SKYBLUE (-5500 6250);
FORCEPROP 0 LAST $SEC 1
J 0
(-5500 6300);
DISPLAY 0.680851 (-5500 6300);
PAINT MONO (-5500 6300);
DISPLAY INVISIBLE (-5500 6300);
FORCEPROP 0 LAST CDS_SEC 1
J 0
(-5500 6300);
DISPLAY 0.680851 (-5500 6300);
DISPLAY INVISIBLE (-5500 6300);
FORCEPROP 1 LASTPIN (-5550 6250) $PN 1
J 0
(-5540 6230);
DISPLAY 0.787234 (-5540 6230);
PAINT MONO (-5540 6230);
FORCEPROP 1 LASTPIN (-5550 6050) $PN 2
J 0
(-5540 6030);
DISPLAY 0.787234 (-5540 6030);
PAINT MONO (-5540 6030);
FORCEPROP 1 LAST PACK_TYPE C0201
J 0
(-5500 6000);
DISPLAY 0.510638 (-5500 6000);
FORCEPROP 1 LAST MATERIAL X7S
J 0
(-5500 6050);
DISPLAY 0.510638 (-5500 6050);
FORCEPROP 1 LAST VOLTAGE 10V
J 0
(-5500 6150);
DISPLAY 0.510638 (-5500 6150);
FORCEPROP 1 LAST TOLERANCE 10%
J 0
(-5500 6100);
DISPLAY 0.510638 (-5500 6100);
FORCEPROP 1 LAST VALUE 0.1UF
J 0
(-5500 6200);
DISPLAY 0.510638 (-5500 6200);
FORCEPROP 2 LAST CDS_LIB pure_quanta
J 0
(-5550 6150);
DISPLAY INVISIBLE (-5550 6150);
FORCEPROP 1 LAST PATH I23
J 0
(-5500 6300);
DISPLAY 0.978723 (-5500 6300);
PAINT WHITE (-5500 6300);
DISPLAY INVISIBLE (-5500 6300);
FORCEPROP 1 LAST PART_NUMBER CH4102K6E00
J 0
(-5500 6000);
DISPLAY 0.978723 (-5500 6000);
DISPLAY INVISIBLE (-5500 6000);
FORCEADD UNIVERSAL_GND..1
(-5550 5875);
FORCEPROP 3 LASTPIN (-5550 5925) SIG_NAME GND\g
J 0
(-5540 5935);
DISPLAY 0.659574 (-5540 5935);
PAINT MONO (-5540 5935);
DISPLAY INVISIBLE (-5540 5935);
FORCEPROP 2 LAST CDS_LIB pure_quanta_power
J 0
(-5550 5875);
DISPLAY INVISIBLE (-5550 5875);
FORCEPROP 1 LAST HDL_POWER GND
J 1
(-5525 5800);
DISPLAY 0.872340 (-5525 5800);
PAINT GREEN (-5525 5800);
DISPLAY INVISIBLE (-5525 5800);
FORCEPROP 1 LAST PATH I24
J 0
(-5475 5875);
DISPLAY 0.872340 (-5475 5875);
PAINT AQUA (-5475 5875);
DISPLAY INVISIBLE (-5475 5875);
FORCEADD Q_RES..1
(-6200 5625);
FORCEPROP 1 LAST LOCATION R682
J 0
(-6450 5625);
DISPLAY 0.978723 (-6450 5625);
FORCEPROP 0 LAST $SEC 1
J 0
(-6250 5800);
DISPLAY 0.680851 (-6250 5800);
PAINT MONO (-6250 5800);
DISPLAY INVISIBLE (-6250 5800);
FORCEPROP 0 LAST CDS_SEC 1
J 0
(-6250 5800);
DISPLAY 0.680851 (-6250 5800);
DISPLAY INVISIBLE (-6250 5800);
FORCEPROP 1 LASTPIN (-6300 5625) $PN 1
J 0
(-6288 5637);
DISPLAY 0.787234 (-6288 5637);
PAINT MONO (-6288 5637);
FORCEPROP 1 LASTPIN (-6100 5625) $PN 2
J 0
(-6138 5637);
DISPLAY 0.787234 (-6138 5637);
PAINT MONO (-6138 5637);
FORCEPROP 1 LAST MATERIAL CHIP
J 0
(-6375 5700);
DISPLAY 0.787234 (-6375 5700);
FORCEPROP 1 LAST PACK_TYPE 0201LF
J 0
(-6175 5700);
DISPLAY 0.787234 (-6175 5700);
FORCEPROP 1 LAST WATTAGE 1/20W
J 2
(-6400 5700);
DISPLAY 0.787234 (-6400 5700);
FORCEPROP 1 LAST VALUE 33.2
J 2
(-6400 5750);
DISPLAY 0.787234 (-6400 5750);
FORCEPROP 1 LAST TOLERANCE 1%
J 0
(-6375 5750);
DISPLAY 0.787234 (-6375 5750);
FORCEPROP 2 LAST CDS_LIB pure_quanta
J 0
(-6200 5625);
DISPLAY INVISIBLE (-6200 5625);
FORCEPROP 1 LAST PATH I3
J 0
(-6250 5775);
DISPLAY 0.978723 (-6250 5775);
PAINT WHITE (-6250 5775);
DISPLAY INVISIBLE (-6250 5775);
FORCEPROP 1 LAST PART_NUMBER CS03321FE09
J 0
(-6250 5750);
DISPLAY 0.808511 (-6250 5750);
DISPLAY INVISIBLE (-6250 5750);
FORCEADD Q_RES..1
(-6200 5575);
FORCEPROP 1 LAST LOCATION R683
J 0
(-6450 5575);
DISPLAY 0.978723 (-6450 5575);
FORCEPROP 0 LAST $SEC 1
J 0
(-6450 5625);
DISPLAY 0.680851 (-6450 5625);
PAINT MONO (-6450 5625);
DISPLAY INVISIBLE (-6450 5625);
FORCEPROP 0 LAST CDS_SEC 1
J 0
(-6450 5625);
DISPLAY 0.680851 (-6450 5625);
DISPLAY INVISIBLE (-6450 5625);
FORCEPROP 1 LASTPIN (-6300 5575) $PN 1
J 0
(-6288 5587);
DISPLAY 0.787234 (-6288 5587);
PAINT MONO (-6288 5587);
FORCEPROP 1 LASTPIN (-6100 5575) $PN 2
J 0
(-6138 5587);
DISPLAY 0.787234 (-6138 5587);
PAINT MONO (-6138 5587);
FORCEPROP 2 LAST CDS_LIB pure_quanta
J 0
(-6200 5575);
DISPLAY INVISIBLE (-6200 5575);
FORCEPROP 1 LAST MATERIAL CHIP
J 0
(-6375 5650);
DISPLAY 0.787234 (-6375 5650);
DISPLAY INVISIBLE (-6375 5650);
FORCEPROP 1 LAST WATTAGE 1/20W
J 2
(-6400 5650);
DISPLAY 0.787234 (-6400 5650);
DISPLAY INVISIBLE (-6400 5650);
FORCEPROP 1 LAST PACK_TYPE 0201LF
J 0
(-6175 5650);
DISPLAY 0.787234 (-6175 5650);
DISPLAY INVISIBLE (-6175 5650);
FORCEPROP 1 LAST VALUE 33.2
J 2
(-6400 5700);
DISPLAY 0.787234 (-6400 5700);
DISPLAY INVISIBLE (-6400 5700);
FORCEPROP 1 LAST TOLERANCE 1%
J 0
(-6375 5700);
DISPLAY 0.787234 (-6375 5700);
DISPLAY INVISIBLE (-6375 5700);
FORCEPROP 1 LAST PATH I4
J 0
(-6250 5725);
DISPLAY 0.978723 (-6250 5725);
PAINT WHITE (-6250 5725);
DISPLAY INVISIBLE (-6250 5725);
FORCEPROP 1 LAST PART_NUMBER CS03321FE09
J 0
(-6250 5700);
DISPLAY 0.808511 (-6250 5700);
DISPLAY INVISIBLE (-6250 5700);
FORCEADD M24M02DRMN6TP..1
(-4775 5650);
FORCEPROP 1 LAST LOCATION U16
J 0
(-4969 5990);
DISPLAY 0.723404 (-4969 5990);
PAINT GREEN (-4969 5990);
FORCEPROP 0 LAST $SEC 1
J 0
(-4950 6125);
DISPLAY 0.680851 (-4950 6125);
PAINT MONO (-4950 6125);
DISPLAY INVISIBLE (-4950 6125);
FORCEPROP 0 LAST CDS_SEC 1
J 0
(-4950 6125);
DISPLAY 0.680851 (-4950 6125);
DISPLAY INVISIBLE (-4950 6125);
FORCEPROP 0 LASTPIN (-4450 5725) $PN 1
J 0
(-4440 5735);
DISPLAY 0.680851 (-4440 5735);
PAINT MONO (-4440 5735);
FORCEPROP 0 LASTPIN (-4450 5675) $PN 2
J 0
(-4440 5685);
DISPLAY 0.680851 (-4440 5685);
PAINT MONO (-4440 5685);
FORCEPROP 0 LASTPIN (-4450 5625) $PN 3
J 0
(-4440 5635);
DISPLAY 0.680851 (-4440 5635);
PAINT MONO (-4440 5635);
FORCEPROP 0 LASTPIN (-5100 5625) $PN 6
J 2
(-5110 5635);
DISPLAY 0.680851 (-5110 5635);
PAINT MONO (-5110 5635);
FORCEPROP 0 LASTPIN (-5100 5575) $PN 5
J 2
(-5110 5585);
DISPLAY 0.680851 (-5110 5585);
PAINT MONO (-5110 5585);
FORCEPROP 0 LASTPIN (-5100 5725) $PN 8
J 2
(-5110 5735);
DISPLAY 0.680851 (-5110 5735);
PAINT MONO (-5110 5735);
FORCEPROP 0 LASTPIN (-4450 5575) $PN 4
J 0
(-4440 5585);
DISPLAY 0.680851 (-4440 5585);
PAINT MONO (-4440 5585);
FORCEPROP 0 LASTPIN (-5100 5675) $PN 7
J 2
(-5110 5685);
DISPLAY 0.680851 (-5110 5685);
PAINT MONO (-5110 5685);
FORCEPROP 2 LAST VALUE M24M02-DRMN6TP
J 0
(-4950 6025);
DISPLAY 0.680851 (-4950 6025);
FORCEPROP 2 LAST PART_TYPE SMLF
J 0
(-4950 6075);
DISPLAY 0.680851 (-4950 6075);
FORCEPROP 1 LAST MATERIAL IC
J 0
(-4969 5782);
DISPLAY 0.723404 (-4969 5782);
PAINT GREEN (-4969 5782);
FORCEPROP 2 LAST CDS_LIB pure_quanta
J 0
(-4775 5650);
DISPLAY INVISIBLE (-4775 5650);
FORCEPROP 1 LAST CDS_LMAN_SYM_OUTLINE -175,125,175,-125
J 0
(-4775 5650);
DISPLAY 0.468085 (-4775 5650);
PAINT GREEN (-4775 5650);
DISPLAY INVISIBLE (-4775 5650);
FORCEPROP 1 LAST NEEDS_NO_SIZE TRUE
J 0
(-4600 5582);
DISPLAY 0.723404 (-4600 5582);
PAINT GREEN (-4600 5582);
DISPLAY INVISIBLE (-4600 5582);
FORCEPROP 1 LAST PATH I5
J 0
(-4600 5525);
DISPLAY 0.723404 (-4600 5525);
PAINT GREEN (-4600 5525);
DISPLAY INVISIBLE (-4600 5525);
FORCEPROP 1 LAST PART_NUMBER AKE33Z00600
J 0
(-4969 5876);
DISPLAY 0.723404 (-4969 5876);
PAINT GREEN (-4969 5876);
DISPLAY INVISIBLE (-4969 5876);
FORCEADD QUANTA_TITLE_BLOCK_C..1
(0 0);
FORCEPROP 0 LAST CDS_CON_LAST_MODIFIED Thu Sep 14 16:13:00 2023
J 0
(-1885 15);
DISPLAY INVISIBLE (-1885 15);
FORCEPROP 1 LAST CUSTOM_TXT_CDS <CON_LAST_MODIFIED>
J 0
(-1885 15);
DISPLAY 0.978723 (-1885 15);
FORCEPROP 2 LAST CUSTOM_TXT_CDS <XR_PAGE_TITLE>
J 0
(-7890 5250);
DISPLAY 0.638298 (-7890 5250);
PAINT PINK (-7890 5250);
DISPLAY INVISIBLE (-7890 5250);
FORCEPROP 1 LAST CUSTOM_TXT_CDS <NAME_2>
J 0
(-3175 50);
FORCEPROP 1 LAST CUSTOM_TXT_CDS <NAME_1>
J 0
(-3175 175);
FORCEPROP 1 LAST CUSTOM_TXT_CDS <Q_NUMBER>
J 0
(-1403 103);
DISPLAY 1.212766 (-1403 103);
FORCEPROP 1 LAST CUSTOM_TXT_CDS <Q_PROJ>
J 0
(-2382 102);
DISPLAY 1.212766 (-2382 102);
FORCEPROP 1 LAST CUSTOM_TXT_CDS <Q_REV>
J 0
(-184 103);
DISPLAY 1.212766 (-184 103);
FORCEPROP 1 LAST CUSTOM_TXT_CDS <CON_PAGE_NUM> OF <CON_TOTAL_PAGES>
J 0
(-446 18);
DISPLAY 0.978723 (-446 18);
FORCEPROP 1 LAST Q_TITLE RETIMER_CPU0_P2(7)
J 0
(-9366 26);
DISPLAY 2.446809 (-9366 26);
PAINT GREEN (-9366 26);
FORCEPROP 2 LAST PAGE_BORDER TRUE
J 0
(-7890 5250);
DISPLAY 0.638298 (-7890 5250);
PAINT PINK (-7890 5250);
DISPLAY INVISIBLE (-7890 5250);
FORCEPROP 1 LAST CDS_LMAN_SYM_OUTLINE -9475,6775,100,-125
J 0
(0 0);
DISPLAY 0.468085 (0 0);
PAINT GREEN (0 0);
DISPLAY INVISIBLE (0 0);
FORCEPROP 2 LAST CDS_LIB pure_quanta
J 0
(0 0);
DISPLAY INVISIBLE (0 0);
FORCEPROP 2 LAST CDS_XR_PAGE_TITLE CR-301 : @T6G_MB_LIB.T6G(SCH_1):PAGE301
J 0
(-7890 5250);
DISPLAY 0.638298 (-7890 5250);
PAINT PINK (-7890 5250);
DISPLAY INVISIBLE (-7890 5250);
FORCEPROP 1 LAST Q_DEPT BU9
J 1
(-3763 49);
DISPLAY 1.957447 (-3763 49);
PAINT GREEN (-3763 49);
DISPLAY INVISIBLE (-3763 49);
FORCEPROP 1 LAST COMMENT_BODY TRUE
J 0
(12 -13);
DISPLAY 0.978723 (12 -13);
PAINT GREEN (12 -13);
DISPLAY INVISIBLE (12 -13);
WIRE 16 -1 (-4100 5350)(-4100 5075);
WIRE 16 -1 (-4450 5575)(-4250 5575);
WIRE 16 -1 (-4250 5575)(-4250 5425);
WIRE 16 -1 (-5100 5675)(-5200 5675);
WIRE 16 -1 (-5550 6050)(-5550 5925);
WIRE 16 -1 (-6300 5575)(-7350 5575);
FORCEPROP 2 LAST SIG_NAME SMB_RT_CPU0_P2_ROM_R_SDA
J 0
(-7260 5585);
DISPLAY 0.680851 (-7260 5585);
WIRE 16 -1 (-5100 5575)(-6100 5575);
FORCEPROP 2 LAST SIG_NAME SMB_RT_CPU0_P2_ROM_SDA
J 0
(-5985 5585);
DISPLAY 0.680851 (-5985 5585);
FORCEPROP 2 LASTPROP $XRERR UNIQUE?
J 0
(-6225 5585);
DISPLAY 0.638298 (-6225 5585);
PAINT MONO (-6225 5585);
DISPLAY INVISIBLE (-6225 5585);
WIRE 16 -1 (-6300 5625)(-7375 5625);
FORCEPROP 2 LAST SIG_NAME SMB_RT_CPU0_P2_ROM_R_SCL
J 0
(-7260 5635);
DISPLAY 0.680851 (-7260 5635);
WIRE 16 -1 (-5100 5625)(-6100 5625);
FORCEPROP 2 LAST SIG_NAME SMB_RT_CPU0_P2_ROM_SCL
J 0
(-5985 5635);
DISPLAY 0.680851 (-5985 5635);
FORCEPROP 2 LASTPROP $XRERR UNIQUE?
J 0
(-6225 5635);
DISPLAY 0.638298 (-6225 5635);
PAINT MONO (-6225 5635);
DISPLAY INVISIBLE (-6225 5635);
WIRE 16 -1 (-4450 5625)(-4100 5625);
FORCEPROP 2 LAST SIG_NAME U16_E2
J 0
(-4310 5635);
DISPLAY 0.680851 (-4310 5635);
FORCEPROP 2 LASTPROP $XRERR UNIQUE?
J 0
(-4550 5635);
DISPLAY 0.638298 (-4550 5635);
PAINT MONO (-4550 5635);
DISPLAY INVISIBLE (-4550 5635);
WIRE 16 -1 (-4100 5625)(-4100 5550);
WIRE 16 -1 (-5250 6450)(-5250 6375);
WIRE 16 -1 (-5550 6375)(-5250 6375);
WIRE 16 -1 (-5250 6375)(-5250 5725);
WIRE 16 -1 (-5250 5725)(-5100 5725);
WIRE 16 -1 (-5550 6250)(-5550 6375);
DOT 1 (-5250 6375);
FORCENOTE
RETIMER EEPRO ADDRESS: 0XA0 (8 BIT) / 0X50 (7 BIT)
(-8225 5175) 0;
DISPLAY LEFT (-8225 5175);
DISPLAY 1.595745 (-8225 5175);
QUIT
